#ISCELL
  mstr_misc dns *
  *
#ISCELL
  pure_quanta quanta_title_block_c *
  *
#CELL
  pure_quanta q_res *
  page130_i11
#CELL
  pure_quanta q_res *
  page130_i22
#CELL
  pure_quanta q_res *
  page130_i26
#CELL
  pure_quanta q_res *
  page130_i37
#ISCELL
  standard offpage *
  page130_i53
#ISCELL
  standard offpage *
  page130_i54
#ISCELL
  standard offpage *
  page130_i55
#ISCELL
  standard offpage *
  page130_i56
#ISCELL
  logical_power universal_gnd *
  page130_i57
#ISCELL
  logical_power universal_gnd *
  page130_i58
#CELL
  pure_quanta q_cap *
  page130_i59
#ISCELL
  logical_power universal_gnd *
  page130_i61
#CELL
  pure_quanta q_cap *
  page130_i62
#CELL
  pure_quanta q_res *
  page130_i63
#ISCELL
  logical_power universal_gnd *
  page130_i64
#CELL
  pure_quanta q_cap *
  page130_i65
#CELL
  pure_quanta q_cap *
  page130_i68
#CELL
  pure_quanta q_res *
  page130_i75
#CELL
  pure_quanta q_res *
  page130_i76
#CELL
  pure_quanta q_res *
  page130_i79
#ISCELL
  standard offpage *
  page130_i80
#ISCELL
  logical_power universal_power *
  page130_i81
#CELL
  pure_quanta q_res *
  page130_i82
#ISCELL
  logical_power universal_power *
  page130_i83
#CELL
  pure_quanta q_res *
  page130_i84
#ISCELL
  standard offpage *
  page130_i85
#ISCELL
  standard offpage *
  page130_i86
#ISCELL
  logical_power universal_power *
  page130_i87
#CELL
  pure_quanta q_res *
  page130_i88
#ISCELL
  logical_power universal_power *
  page130_i89
#CELL
  pure_quanta q_res *
  page130_i90
#ISCELL
  standard offpage *
  page130_i91
